(kicad_pcb
	(version 20260206)
	(generator "pcbnew")
	(generator_version "10.0")
	(general
		(thickness 1.6)
		(legacy_teardrops no)
	)
	(paper "A4")
	(title_block
		(title "03242023_DA0F0TMBIJ0_F0T_Motherboard_J_brd_V01_OCP.brd")
		(comment 1 "Grand Teton / footprints 6010-6017 of 6105")
	)
	(layers
		(0 "F.Cu" signal "TOP")
		(4 "In1.Cu" signal "GND")
		(6 "In2.Cu" signal "IN1")
		(8 "In3.Cu" signal "GND1")
		(10 "In4.Cu" signal "IN2")
		(12 "In5.Cu" signal "GND2")
		(14 "In6.Cu" signal "IN3")
		(16 "In7.Cu" signal "GND3")
		(18 "In8.Cu" signal "VCC")
		(20 "In9.Cu" signal "VCC1")
		(22 "In10.Cu" signal "GND4")
		(24 "In11.Cu" signal "IN4")
		(26 "In12.Cu" signal "GND5")
		(28 "In13.Cu" signal "IN5")
		(30 "In14.Cu" signal "GND6")
		(32 "In15.Cu" signal "IN6")
		(34 "In16.Cu" signal "GND7")
		(2 "B.Cu" signal "BOTTOM")
		(9 "F.Adhes" user "F.Adhesive")
		(11 "B.Adhes" user "B.Adhesive")
		(13 "F.Paste" user "Package Geometry/Pastemask Top")
		(15 "B.Paste" user "Package Geometry/Pastemask Bottom")
		(5 "F.SilkS" user "Ref Des/Silkscreen Top")
		(7 "B.SilkS" user "Ref Des/Silkscreen Bottom")
		(1 "F.Mask" user "Board Geometry/Soldermask Top")
		(3 "B.Mask" user "Board Geometry/Soldermask Bottom")
		(17 "Dwgs.User" user "User.Drawings")
		(19 "Cmts.User" user "User.Comments")
		(21 "Eco1.User" user "User.Eco1")
		(23 "Eco2.User" user "User.Eco2")
		(25 "Edge.Cuts" user "Board Geometry/Outline")
		(27 "Margin" user)
		(31 "F.CrtYd" user "Package Geometry/Place Bound Top")
		(29 "B.CrtYd" user "Package Geometry/Place Bound Bottom")
		(35 "F.Fab" user "Ref Des/Assembly Top")
		(33 "B.Fab" user "Ref Des/Assembly Bottom")
	)
	(footprint ""
		(layer "B.Cu")
		(at 39.526972 -129.81813 180)
		(property "Reference" "R2345"
			(at 0 0 0)
			(layer "B.SilkS")
			(hide yes)
			(effects
				(font
					(size 1.27 1.27)
				)
				(justify mirror)
			)
		)
		(property "Value" ""
			(at 0 0 0)
			(layer "B.Fab")
			(effects
				(font
					(size 1.27 1.27)
				)
				(justify mirror)
			)
		)
		(duplicate_pad_numbers_are_jumpers no)
		(fp_line
			(start 0.7874 0.4064)
			(end 0.7874 -0.4064)
			(stroke
				(width 0.1524)
				(type default)
			)
			(layer "B.SilkS")
		)
		(fp_line
			(start 0.7874 -0.4064)
			(end -0.7874 -0.4064)
			(stroke
				(width 0.1524)
				(type default)
			)
			(layer "B.SilkS")
		)
		(fp_line
			(start -0.7874 0.4064)
			(end 0.7874 0.4064)
			(stroke
				(width 0.1524)
				(type default)
			)
			(layer "B.SilkS")
		)
		(fp_line
			(start -0.7874 -0.4064)
			(end -0.7874 0.4064)
			(stroke
				(width 0.1524)
				(type default)
			)
			(layer "B.SilkS")
		)
		(fp_line
			(start 0.67945 0.3048)
			(end 0.67945 -0.305054)
			(stroke
				(width 0.1)
				(type default)
			)
			(layer "B.Fab")
		)
		(fp_line
			(start 0.67945 -0.305054)
			(end 0.12065 -0.305054)
			(stroke
				(width 0.1)
				(type default)
			)
			(layer "B.Fab")
		)
		(fp_line
			(start 0.12065 0.3048)
			(end 0.67945 0.3048)
			(stroke
				(width 0.1)
				(type default)
			)
			(layer "B.Fab")
		)
		(fp_line
			(start 0.12065 0.2794)
			(end 0.12065 0.3048)
			(stroke
				(width 0.1)
				(type default)
			)
			(layer "B.Fab")
		)
		(fp_line
			(start 0.12065 -0.2794)
			(end -0.12065 -0.2794)
			(stroke
				(width 0.1)
				(type default)
			)
			(layer "B.Fab")
		)
		(fp_line
			(start 0.12065 -0.305054)
			(end 0.12065 -0.2794)
			(stroke
				(width 0.1)
				(type default)
			)
			(layer "B.Fab")
		)
		(fp_line
			(start -0.120396 0.3048)
			(end -0.120396 0.2794)
			(stroke
				(width 0.1)
				(type default)
			)
			(layer "B.Fab")
		)
		(fp_line
			(start -0.120396 0.2794)
			(end 0.12065 0.2794)
			(stroke
				(width 0.1)
				(type default)
			)
			(layer "B.Fab")
		)
		(fp_line
			(start -0.12065 -0.2794)
			(end -0.12065 -0.3048)
			(stroke
				(width 0.1)
				(type default)
			)
			(layer "B.Fab")
		)
		(fp_line
			(start -0.12065 -0.3048)
			(end -0.67945 -0.3048)
			(stroke
				(width 0.1)
				(type default)
			)
			(layer "B.Fab")
		)
		(fp_line
			(start -0.67945 0.3048)
			(end -0.120396 0.3048)
			(stroke
				(width 0.1)
				(type default)
			)
			(layer "B.Fab")
		)
		(fp_line
			(start -0.67945 -0.3048)
			(end -0.67945 0.3048)
			(stroke
				(width 0.1)
				(type default)
			)
			(layer "B.Fab")
		)
		(pad "1" smd circle
			(at 0.40005 0)
			(size 0 0)
			(layers "B.Cu" "B.Mask" "B.Paste")
			(net "PVNN_TERM_CPU1")
		)
		(pad "2" smd circle
			(at -0.40005 0)
			(size 0 0)
			(layers "B.Cu" "B.Mask" "B.Paste")
			(net "SVID_CLK0_CPU1_R")
		)
	)
	(footprint ""
		(layer "B.Cu")
		(at 330.280518 -187.67933 90)
		(property "Reference" "R183"
			(at 0 0 90)
			(layer "B.SilkS")
			(hide yes)
			(effects
				(font
					(size 1.27 1.27)
				)
				(justify mirror)
			)
		)
		(property "Value" ""
			(at 0 0 90)
			(layer "B.Fab")
			(effects
				(font
					(size 1.27 1.27)
				)
				(justify mirror)
			)
		)
		(duplicate_pad_numbers_are_jumpers no)
		(fp_line
			(start 0.7874 -0.4064)
			(end -0.7874 -0.4064)
			(stroke
				(width 0.1524)
				(type default)
			)
			(layer "B.SilkS")
		)
		(fp_line
			(start -0.7874 -0.4064)
			(end -0.7874 0.4064)
			(stroke
				(width 0.1524)
				(type default)
			)
			(layer "B.SilkS")
		)
		(fp_line
			(start 0.7874 0.4064)
			(end 0.7874 -0.4064)
			(stroke
				(width 0.1524)
				(type default)
			)
			(layer "B.SilkS")
		)
		(fp_line
			(start -0.7874 0.4064)
			(end 0.7874 0.4064)
			(stroke
				(width 0.1524)
				(type default)
			)
			(layer "B.SilkS")
		)
		(fp_line
			(start 0.67945 -0.305054)
			(end 0.12065 -0.305054)
			(stroke
				(width 0.1)
				(type default)
			)
			(layer "B.Fab")
		)
		(fp_line
			(start 0.12065 -0.305054)
			(end 0.12065 -0.2794)
			(stroke
				(width 0.1)
				(type default)
			)
			(layer "B.Fab")
		)
		(fp_line
			(start -0.12065 -0.3048)
			(end -0.67945 -0.3048)
			(stroke
				(width 0.1)
				(type default)
			)
			(layer "B.Fab")
		)
		(fp_line
			(start -0.67945 -0.3048)
			(end -0.67945 0.3048)
			(stroke
				(width 0.1)
				(type default)
			)
			(layer "B.Fab")
		)
		(fp_line
			(start 0.12065 -0.2794)
			(end -0.12065 -0.2794)
			(stroke
				(width 0.1)
				(type default)
			)
			(layer "B.Fab")
		)
		(fp_line
			(start -0.12065 -0.2794)
			(end -0.12065 -0.3048)
			(stroke
				(width 0.1)
				(type default)
			)
			(layer "B.Fab")
		)
		(fp_line
			(start 0.12065 0.2794)
			(end 0.12065 0.3048)
			(stroke
				(width 0.1)
				(type default)
			)
			(layer "B.Fab")
		)
		(fp_line
			(start -0.120396 0.2794)
			(end 0.12065 0.2794)
			(stroke
				(width 0.1)
				(type default)
			)
			(layer "B.Fab")
		)
		(fp_line
			(start 0.67945 0.3048)
			(end 0.67945 -0.305054)
			(stroke
				(width 0.1)
				(type default)
			)
			(layer "B.Fab")
		)
		(fp_line
			(start 0.12065 0.3048)
			(end 0.67945 0.3048)
			(stroke
				(width 0.1)
				(type default)
			)
			(layer "B.Fab")
		)
		(fp_line
			(start -0.120396 0.3048)
			(end -0.120396 0.2794)
			(stroke
				(width 0.1)
				(type default)
			)
			(layer "B.Fab")
		)
		(fp_line
			(start -0.67945 0.3048)
			(end -0.120396 0.3048)
			(stroke
				(width 0.1)
				(type default)
			)
			(layer "B.Fab")
		)
		(pad "1" smd circle
			(at 0.40005 0 270)
			(size 0 0)
			(layers "B.Cu" "B.Mask" "B.Paste")
			(net "PWRGD_CPU0_BUF_R")
		)
		(pad "2" smd circle
			(at -0.40005 0 270)
			(size 0 0)
			(layers "B.Cu" "B.Mask" "B.Paste")
			(net "PVNN_TERM_CPU0")
		)
	)
	(footprint ""
		(layer "B.Cu")
		(at 112.9284 -411.716728 -90)
		(property "Reference" "C2334"
			(at 0 0 90)
			(layer "B.SilkS")
			(hide yes)
			(effects
				(font
					(size 1.27 1.27)
				)
				(justify mirror)
			)
		)
		(property "Value" ""
			(at 0 0 90)
			(layer "B.Fab")
			(effects
				(font
					(size 1.27 1.27)
				)
				(justify mirror)
			)
		)
		(duplicate_pad_numbers_are_jumpers no)
		(fp_line
			(start -0.7874 0.4064)
			(end 0.7874 0.4064)
			(stroke
				(width 0.1524)
				(type default)
			)
			(layer "B.SilkS")
		)
		(fp_line
			(start 0.7874 0.4064)
			(end 0.7874 -0.4064)
			(stroke
				(width 0.1524)
				(type default)
			)
			(layer "B.SilkS")
		)
		(fp_line
			(start -0.7874 -0.4064)
			(end -0.7874 0.4064)
			(stroke
				(width 0.1524)
				(type default)
			)
			(layer "B.SilkS")
		)
		(fp_line
			(start 0.7874 -0.4064)
			(end -0.7874 -0.4064)
			(stroke
				(width 0.1524)
				(type default)
			)
			(layer "B.SilkS")
		)
		(fp_line
			(start -0.67945 0.3048)
			(end -0.120396 0.3048)
			(stroke
				(width 0.1)
				(type default)
			)
			(layer "B.Fab")
		)
		(fp_line
			(start -0.120396 0.3048)
			(end -0.120396 0.2794)
			(stroke
				(width 0.1)
				(type default)
			)
			(layer "B.Fab")
		)
		(fp_line
			(start 0.12065 0.3048)
			(end 0.67945 0.3048)
			(stroke
				(width 0.1)
				(type default)
			)
			(layer "B.Fab")
		)
		(fp_line
			(start 0.67945 0.3048)
			(end 0.67945 -0.305054)
			(stroke
				(width 0.1)
				(type default)
			)
			(layer "B.Fab")
		)
		(fp_line
			(start -0.120396 0.2794)
			(end 0.12065 0.2794)
			(stroke
				(width 0.1)
				(type default)
			)
			(layer "B.Fab")
		)
		(fp_line
			(start 0.12065 0.2794)
			(end 0.12065 0.3048)
			(stroke
				(width 0.1)
				(type default)
			)
			(layer "B.Fab")
		)
		(fp_line
			(start -0.12065 -0.2794)
			(end -0.12065 -0.3048)
			(stroke
				(width 0.1)
				(type default)
			)
			(layer "B.Fab")
		)
		(fp_line
			(start 0.12065 -0.2794)
			(end -0.12065 -0.2794)
			(stroke
				(width 0.1)
				(type default)
			)
			(layer "B.Fab")
		)
		(fp_line
			(start -0.67945 -0.3048)
			(end -0.67945 0.3048)
			(stroke
				(width 0.1)
				(type default)
			)
			(layer "B.Fab")
		)
		(fp_line
			(start -0.12065 -0.3048)
			(end -0.67945 -0.3048)
			(stroke
				(width 0.1)
				(type default)
			)
			(layer "B.Fab")
		)
		(fp_line
			(start 0.12065 -0.305054)
			(end 0.12065 -0.2794)
			(stroke
				(width 0.1)
				(type default)
			)
			(layer "B.Fab")
		)
		(fp_line
			(start 0.67945 -0.305054)
			(end 0.12065 -0.305054)
			(stroke
				(width 0.1)
				(type default)
			)
			(layer "B.Fab")
		)
		(pad "1" smd circle
			(at 0.40005 0 90)
			(size 0 0)
			(layers "B.Cu" "B.Mask" "B.Paste")
			(net "P3V3_9ZXL045_VDDA")
		)
		(pad "2" smd circle
			(at -0.40005 0 90)
			(size 0 0)
			(layers "B.Cu" "B.Mask" "B.Paste")
			(net "GND")
		)
	)
	(footprint ""
		(layer "B.Cu")
		(at 103.901494 -248.49836 -90)
		(property "Reference" "C451"
			(at 0 0 90)
			(layer "B.SilkS")
			(hide yes)
			(effects
				(font
					(size 1.27 1.27)
				)
				(justify mirror)
			)
		)
		(property "Value" ""
			(at 0 0 90)
			(layer "B.Fab")
			(effects
				(font
					(size 1.27 1.27)
				)
				(justify mirror)
			)
		)
		(duplicate_pad_numbers_are_jumpers no)
		(fp_line
			(start -1.524 0.762)
			(end 1.524 0.762)
			(stroke
				(width 0.1524)
				(type default)
			)
			(layer "B.SilkS")
		)
		(fp_line
			(start 1.524 0.762)
			(end 1.524 -0.762)
			(stroke
				(width 0.1524)
				(type default)
			)
			(layer "B.SilkS")
		)
		(fp_line
			(start -1.524 -0.762)
			(end -1.524 0.762)
			(stroke
				(width 0.1524)
				(type default)
			)
			(layer "B.SilkS")
		)
		(fp_line
			(start 1.524 -0.762)
			(end -1.524 -0.762)
			(stroke
				(width 0.1524)
				(type default)
			)
			(layer "B.SilkS")
		)
		(fp_line
			(start -1.1049 0.724916)
			(end -1.1049 -0.724916)
			(stroke
				(width 0.1)
				(type default)
			)
			(layer "B.Fab")
		)
		(fp_line
			(start 1.1049 0.724916)
			(end -1.1049 0.724916)
			(stroke
				(width 0.1)
				(type default)
			)
			(layer "B.Fab")
		)
		(fp_line
			(start -1.1049 -0.724916)
			(end 1.1049 -0.724916)
			(stroke
				(width 0.1)
				(type default)
			)
			(layer "B.Fab")
		)
		(fp_line
			(start 1.1049 -0.724916)
			(end 1.1049 0.724916)
			(stroke
				(width 0.1)
				(type default)
			)
			(layer "B.Fab")
		)
		(pad "1" smd rect
			(at 0.889 0 270)
			(size 1.016 1.27)
			(layers "B.Cu" "B.Mask" "B.Paste")
			(net "PVCCD_HV_CPU1")
		)
		(pad "2" smd rect
			(at -0.889 0 270)
			(size 1.016 1.27)
			(layers "B.Cu" "B.Mask" "B.Paste")
			(net "GND")
		)
	)
	(footprint ""
		(layer "B.Cu")
		(at 346.4687 -64.088264 90)
		(property "Reference" "C159"
			(at 0 0 90)
			(layer "B.SilkS")
			(hide yes)
			(effects
				(font
					(size 1.27 1.27)
				)
				(justify mirror)
			)
		)
		(property "Value" ""
			(at 0 0 90)
			(layer "B.Fab")
			(effects
				(font
					(size 1.27 1.27)
				)
				(justify mirror)
			)
		)
		(duplicate_pad_numbers_are_jumpers no)
		(fp_line
			(start 0.299974 -0.150114)
			(end -0.299974 -0.150114)
			(stroke
				(width 0.1)
				(type default)
			)
			(layer "B.Fab")
		)
		(fp_line
			(start -0.299974 -0.150114)
			(end -0.299974 0.150114)
			(stroke
				(width 0.1)
				(type default)
			)
			(layer "B.Fab")
		)
		(fp_line
			(start 0.299974 0.150114)
			(end 0.299974 -0.150114)
			(stroke
				(width 0.1)
				(type default)
			)
			(layer "B.Fab")
		)
		(fp_line
			(start -0.299974 0.150114)
			(end 0.299974 0.150114)
			(stroke
				(width 0.1)
				(type default)
			)
			(layer "B.Fab")
		)
		(pad "1" smd rect
			(at 0.2667 0 270)
			(size 0.3048 0.381)
			(layers "B.Cu" "B.Mask" "B.Paste")
			(net "DMI_CPU0_PCH_RX_C_DN<5>")
		)
		(pad "2" smd rect
			(at -0.2667 0 270)
			(size 0.3048 0.381)
			(layers "B.Cu" "B.Mask" "B.Paste")
			(net "DMI_CPU0_PCH_RX_DN<5>")
		)
	)
	(footprint ""
		(layer "B.Cu")
		(at 366.310418 -294.009826)
		(property "Reference" "C380"
			(at 0 0 0)
			(layer "B.SilkS")
			(hide yes)
			(effects
				(font
					(size 1.27 1.27)
				)
				(justify mirror)
			)
		)
		(property "Value" ""
			(at 0 0 0)
			(layer "B.Fab")
			(effects
				(font
					(size 1.27 1.27)
				)
				(justify mirror)
			)
		)
		(duplicate_pad_numbers_are_jumpers no)
		(fp_line
			(start -1.524 -0.762)
			(end -1.524 0.762)
			(stroke
				(width 0.1524)
				(type default)
			)
			(layer "B.SilkS")
		)
		(fp_line
			(start -1.524 0.762)
			(end 1.524 0.762)
			(stroke
				(width 0.1524)
				(type default)
			)
			(layer "B.SilkS")
		)
		(fp_line
			(start 1.524 -0.762)
			(end -1.524 -0.762)
			(stroke
				(width 0.1524)
				(type default)
			)
			(layer "B.SilkS")
		)
		(fp_line
			(start 1.524 0.762)
			(end 1.524 -0.762)
			(stroke
				(width 0.1524)
				(type default)
			)
			(layer "B.SilkS")
		)
		(fp_line
			(start -1.1049 -0.724916)
			(end 1.1049 -0.724916)
			(stroke
				(width 0.1)
				(type default)
			)
			(layer "B.Fab")
		)
		(fp_line
			(start -1.1049 0.724916)
			(end -1.1049 -0.724916)
			(stroke
				(width 0.1)
				(type default)
			)
			(layer "B.Fab")
		)
		(fp_line
			(start 1.1049 -0.724916)
			(end 1.1049 0.724916)
			(stroke
				(width 0.1)
				(type default)
			)
			(layer "B.Fab")
		)
		(fp_line
			(start 1.1049 0.724916)
			(end -1.1049 0.724916)
			(stroke
				(width 0.1)
				(type default)
			)
			(layer "B.Fab")
		)
		(pad "1" smd rect
			(at 0.889 0)
			(size 1.016 1.27)
			(layers "B.Cu" "B.Mask" "B.Paste")
			(net "PVCCIN_CPU0")
		)
		(pad "2" smd rect
			(at -0.889 0)
			(size 1.016 1.27)
			(layers "B.Cu" "B.Mask" "B.Paste")
			(net "GND")
		)
	)
	(footprint ""
		(layer "B.Cu")
		(at 356.354888 -333.639922 90)
		(property "Reference" "PC304_P0_2"
			(at 0 0 90)
			(layer "B.SilkS")
			(hide yes)
			(effects
				(font
					(size 1.27 1.27)
				)
				(justify mirror)
			)
		)
		(property "Value" ""
			(at 0 0 90)
			(layer "B.Fab")
			(effects
				(font
					(size 1.27 1.27)
				)
				(justify mirror)
			)
		)
		(duplicate_pad_numbers_are_jumpers no)
		(fp_line
			(start 1.524 -0.762)
			(end -1.524 -0.762)
			(stroke
				(width 0.1524)
				(type default)
			)
			(layer "B.SilkS")
		)
		(fp_line
			(start -1.524 -0.762)
			(end -1.524 0.762)
			(stroke
				(width 0.1524)
				(type default)
			)
			(layer "B.SilkS")
		)
		(fp_line
			(start 1.524 0.762)
			(end 1.524 -0.762)
			(stroke
				(width 0.1524)
				(type default)
			)
			(layer "B.SilkS")
		)
		(fp_line
			(start -1.524 0.762)
			(end 1.524 0.762)
			(stroke
				(width 0.1524)
				(type default)
			)
			(layer "B.SilkS")
		)
		(fp_line
			(start 1.1049 -0.724916)
			(end 1.1049 0.724916)
			(stroke
				(width 0.1)
				(type default)
			)
			(layer "B.Fab")
		)
		(fp_line
			(start -1.1049 -0.724916)
			(end 1.1049 -0.724916)
			(stroke
				(width 0.1)
				(type default)
			)
			(layer "B.Fab")
		)
		(fp_line
			(start 1.1049 0.724916)
			(end -1.1049 0.724916)
			(stroke
				(width 0.1)
				(type default)
			)
			(layer "B.Fab")
		)
		(fp_line
			(start -1.1049 0.724916)
			(end -1.1049 -0.724916)
			(stroke
				(width 0.1)
				(type default)
			)
			(layer "B.Fab")
		)
		(pad "1" smd rect
			(at 0.889 0 90)
			(size 1.016 1.27)
			(layers "B.Cu" "B.Mask" "B.Paste")
			(net "SW_P12V_PVCCIN_CPU0_FLT")
		)
		(pad "2" smd rect
			(at -0.889 0 90)
			(size 1.016 1.27)
			(layers "B.Cu" "B.Mask" "B.Paste")
			(net "GND")
		)
	)
	(footprint ""
		(layer "B.Cu")
		(at 292.231572 -354.163376 -90)
		(property "Reference" "PC1186_P0_4"
			(at 0 0 90)
			(layer "B.SilkS")
			(hide yes)
			(effects
				(font
					(size 1.27 1.27)
				)
				(justify mirror)
			)
		)
		(property "Value" ""
			(at 0 0 90)
			(layer "B.Fab")
			(effects
				(font
					(size 1.27 1.27)
				)
				(justify mirror)
			)
		)
		(duplicate_pad_numbers_are_jumpers no)
		(fp_line
			(start -1.524 0.762)
			(end 1.524 0.762)
			(stroke
				(width 0.1524)
				(type default)
			)
			(layer "B.SilkS")
		)
		(fp_line
			(start 1.524 0.762)
			(end 1.524 -0.762)
			(stroke
				(width 0.1524)
				(type default)
			)
			(layer "B.SilkS")
		)
		(fp_line
			(start -1.524 -0.762)
			(end -1.524 0.762)
			(stroke
				(width 0.1524)
				(type default)
			)
			(layer "B.SilkS")
		)
		(fp_line
			(start 1.524 -0.762)
			(end -1.524 -0.762)
			(stroke
				(width 0.1524)
				(type default)
			)
			(layer "B.SilkS")
		)
		(fp_line
			(start -1.1049 0.724916)
			(end -1.1049 -0.724916)
			(stroke
				(width 0.1)
				(type default)
			)
			(layer "B.Fab")
		)
		(fp_line
			(start 1.1049 0.724916)
			(end -1.1049 0.724916)
			(stroke
				(width 0.1)
				(type default)
			)
			(layer "B.Fab")
		)
		(fp_line
			(start -1.1049 -0.724916)
			(end 1.1049 -0.724916)
			(stroke
				(width 0.1)
				(type default)
			)
			(layer "B.Fab")
		)
		(fp_line
			(start 1.1049 -0.724916)
			(end 1.1049 0.724916)
			(stroke
				(width 0.1)
				(type default)
			)
			(layer "B.Fab")
		)
		(pad "1" smd rect
			(at 0.889 0 270)
			(size 1.016 1.27)
			(layers "B.Cu" "B.Mask" "B.Paste")
			(net "PVCCFA_EHV_FIVRA_CPU0")
		)
		(pad "2" smd rect
			(at -0.889 0 270)
			(size 1.016 1.27)
			(layers "B.Cu" "B.Mask" "B.Paste")
			(net "GND")
		)
	)
)
